# BASEBOARD_FAB2 (Tioga Pass) — schematic netlist excerpt (pin names and nets, part order shuffled) for the footprints in the layout excerpt that follows; sources: Cadence DE-HDL packaged netlist, KiCad conversion of Wiwynn_Tioga_Pass_MB.brd

R1L25  RES  10.0 1% CHIP  pkg 0402  page 155 : A = LED_POSTCODE_2 ; B = LED_POSTCODE_2_R
C6G2  CAP  10UF 4V 20% X6S  pkg 0603LF  page 231 : A = PVPP_ABC ; B = GND
R9E4  RES  10.0K 1% CHIP  pkg 0402  page 139 : A = P3V3_STBY ; B = RST_PLTRST_SPRV_R_N

(kicad_pcb
	(version 20260206)
	(generator "pcbnew")
	(generator_version "10.0")
	(general
		(thickness 1.6)
		(legacy_teardrops no)
	)
	(paper "A4")
	(title_block
		(title "Wiwynn_Tioga_Pass_MB.brd")
		(comment 1 "Tioga Pass / footprints 219-221 of 4770")
	)
	(layers
		(0 "F.Cu" signal "TOP")
		(4 "In1.Cu" signal "L2GND")
		(6 "In2.Cu" signal "L3")
		(8 "In3.Cu" signal "L4GND")
		(10 "In4.Cu" signal "L5")
		(12 "In5.Cu" signal "L6GND")
		(14 "In6.Cu" signal "L7VCC")
		(16 "In7.Cu" signal "L8VCC")
		(18 "In8.Cu" signal "L9GND")
		(20 "In9.Cu" signal "L10")
		(22 "In10.Cu" signal "L11GND")
		(24 "In11.Cu" signal "L12")
		(26 "In12.Cu" signal "L13GND")
		(2 "B.Cu" signal "BOTTOM")
		(9 "F.Adhes" user "F.Adhesive")
		(11 "B.Adhes" user "B.Adhesive")
		(13 "F.Paste" user "Package Geometry/Pastemask Top")
		(15 "B.Paste" user "Package Geometry/Pastemask Bottom")
		(5 "F.SilkS" user "Ref Des/Silkscreen Top")
		(7 "B.SilkS" user "Ref Des/Silkscreen Bottom")
		(1 "F.Mask" user "Board Geometry/Soldermask Top")
		(3 "B.Mask" user "Board Geometry/Soldermask Bottom")
		(17 "Dwgs.User" user "User.Drawings")
		(19 "Cmts.User" user "User.Comments")
		(21 "Eco1.User" user "User.Eco1")
		(23 "Eco2.User" user "User.Eco2")
		(25 "Edge.Cuts" user "Board Geometry/Outline")
		(27 "Margin" user)
		(31 "F.CrtYd" user "Package Geometry/Place Bound Top")
		(29 "B.CrtYd" user "Package Geometry/Place Bound Bottom")
		(35 "F.Fab" user "Ref Des/Assembly Top")
		(33 "B.Fab" user "Ref Des/Assembly Bottom")
	)
	(footprint ""
		(layer "F.Cu")
		(at 320.296032 -12.954 90)
		(property "Reference" "C6G2"
			(at 0 0 90)
			(layer "F.SilkS")
			(hide yes)
			(effects
				(font
					(size 1.27 1.27)
				)
			)
		)
		(property "Value" ""
			(at 0 0 90)
			(layer "F.Fab")
			(effects
				(font
					(size 1.27 1.27)
				)
			)
		)
		(duplicate_pad_numbers_are_jumpers no)
		(fp_poly
			(pts
				(xy -0.4953 -0.2032) (xy 0.4953 -0.2032) (xy 0.4953 1.6002) (xy -0.4953 1.6002)
			)
			(stroke
				(width 0)
				(type default)
			)
			(fill no)
			(layer "F.CrtYd")
		)
		(fp_line
			(start 0.4953 -0.2032)
			(end 0.4953 1.6002)
			(stroke
				(width 0.1)
				(type default)
			)
			(layer "F.Fab")
		)
		(fp_line
			(start -0.4953 -0.2032)
			(end 0.4953 -0.2032)
			(stroke
				(width 0.1)
				(type default)
			)
			(layer "F.Fab")
		)
		(fp_line
			(start 0.4953 1.6002)
			(end -0.4953 1.6002)
			(stroke
				(width 0.1)
				(type default)
			)
			(layer "F.Fab")
		)
		(fp_line
			(start -0.4953 1.6002)
			(end -0.4953 -0.2032)
			(stroke
				(width 0.1)
				(type default)
			)
			(layer "F.Fab")
		)
		(pad "1" smd rect
			(at 0 0 90)
			(size 0.762 0.889)
			(layers "F.Cu" "F.Mask" "F.Paste")
			(net "PVPP_ABC")
		)
		(pad "2" smd rect
			(at 0 1.397 90)
			(size 0.762 0.889)
			(layers "F.Cu" "F.Mask" "F.Paste")
			(net "GND")
		)
		(zone
			(layer "F.Cu")
			(hatch none 0.5)
			(connect_pads
				(clearance 0)
			)
			(min_thickness 0.25)
			(keepout
				(tracks not_allowed)
				(vias allowed)
				(pads allowed)
				(copperpour not_allowed)
				(footprints allowed)
			)
			(placement
				(enabled no)
				(sheetname "")
			)
			(fill
				(thermal_gap 0.5)
				(thermal_bridge_width 0.5)
				(island_removal_mode 0)
			)
			(polygon
				(pts
					(xy 320.740532 -12.573) (xy 320.740532 -13.335) (xy 321.248532 -13.335) (xy 321.248532 -12.573)
				)
			)
		)
	)
	(footprint ""
		(layer "F.Cu")
		(at 489.712 -50.6349)
		(property "Reference" "R9E4"
			(at 0 0 0)
			(layer "F.SilkS")
			(hide yes)
			(effects
				(font
					(size 1.27 1.27)
				)
			)
		)
		(property "Value" ""
			(at 0 0 0)
			(layer "F.Fab")
			(effects
				(font
					(size 1.27 1.27)
				)
			)
		)
		(duplicate_pad_numbers_are_jumpers no)
		(fp_poly
			(pts
				(xy -0.2794 -0.1016) (xy 0.2794 -0.1016) (xy 0.2794 0.9906) (xy -0.2794 0.9906)
			)
			(stroke
				(width 0)
				(type default)
			)
			(fill no)
			(layer "F.CrtYd")
		)
		(fp_line
			(start -0.2794 -0.1016)
			(end -0.2794 0.9906)
			(stroke
				(width 0.1)
				(type default)
			)
			(layer "F.Fab")
		)
		(fp_line
			(start -0.2794 0.9906)
			(end 0.2794 0.9906)
			(stroke
				(width 0.1)
				(type default)
			)
			(layer "F.Fab")
		)
		(fp_line
			(start 0.2794 -0.1016)
			(end -0.2794 -0.1016)
			(stroke
				(width 0.1)
				(type default)
			)
			(layer "F.Fab")
		)
		(fp_line
			(start 0.2794 0.9906)
			(end 0.2794 -0.1016)
			(stroke
				(width 0.1)
				(type default)
			)
			(layer "F.Fab")
		)
		(pad "1" smd rect
			(at 0 0)
			(size 0.508 0.508)
			(layers "F.Cu" "F.Mask" "F.Paste")
			(net "P3V3_STBY")
		)
		(pad "2" smd rect
			(at 0 0.889)
			(size 0.508 0.508)
			(layers "F.Cu" "F.Mask" "F.Paste")
			(net "RST_PLTRST_SPRV_R_N")
		)
		(zone
			(layer "F.Cu")
			(hatch none 0.5)
			(connect_pads
				(clearance 0)
			)
			(min_thickness 0.25)
			(keepout
				(tracks allowed)
				(vias not_allowed)
				(pads allowed)
				(copperpour not_allowed)
				(footprints allowed)
			)
			(placement
				(enabled no)
				(sheetname "")
			)
			(fill
				(thermal_gap 0.5)
				(thermal_bridge_width 0.5)
				(island_removal_mode 0)
			)
			(polygon
				(pts
					(xy 489.458 -50.3809) (xy 489.966 -50.3809) (xy 489.966 -49.9999) (xy 489.458 -49.9999)
				)
			)
		)
		(zone
			(layer "F.Cu")
			(hatch none 0.5)
			(connect_pads
				(clearance 0)
			)
			(min_thickness 0.25)
			(keepout
				(tracks not_allowed)
				(vias allowed)
				(pads allowed)
				(copperpour not_allowed)
				(footprints allowed)
			)
			(placement
				(enabled no)
				(sheetname "")
			)
			(fill
				(thermal_gap 0.5)
				(thermal_bridge_width 0.5)
				(island_removal_mode 0)
			)
			(polygon
				(pts
					(xy 489.458 -49.9999) (xy 489.966 -49.9999) (xy 489.966 -50.3809) (xy 489.458 -50.3809)
				)
			)
		)
	)
	(footprint ""
		(layer "F.Cu")
		(at 489.3945 -143.876268 90)
		(property "Reference" "R1L25"
			(at 0 0 90)
			(layer "F.SilkS")
			(hide yes)
			(effects
				(font
					(size 1.27 1.27)
				)
			)
		)
		(property "Value" ""
			(at 0 0 90)
			(layer "F.Fab")
			(effects
				(font
					(size 1.27 1.27)
				)
			)
		)
		(duplicate_pad_numbers_are_jumpers no)
		(fp_poly
			(pts
				(xy -0.2794 -0.1016) (xy 0.2794 -0.1016) (xy 0.2794 0.9906) (xy -0.2794 0.9906)
			)
			(stroke
				(width 0)
				(type default)
			)
			(fill no)
			(layer "F.CrtYd")
		)
		(fp_line
			(start 0.2794 -0.1016)
			(end -0.2794 -0.1016)
			(stroke
				(width 0.1)
				(type default)
			)
			(layer "F.Fab")
		)
		(fp_line
			(start -0.2794 -0.1016)
			(end -0.2794 0.9906)
			(stroke
				(width 0.1)
				(type default)
			)
			(layer "F.Fab")
		)
		(fp_line
			(start 0.2794 0.9906)
			(end 0.2794 -0.1016)
			(stroke
				(width 0.1)
				(type default)
			)
			(layer "F.Fab")
		)
		(fp_line
			(start -0.2794 0.9906)
			(end 0.2794 0.9906)
			(stroke
				(width 0.1)
				(type default)
			)
			(layer "F.Fab")
		)
		(pad "1" smd rect
			(at 0 0 90)
			(size 0.508 0.508)
			(layers "F.Cu" "F.Mask" "F.Paste")
			(net "LED_POSTCODE_2")
		)
		(pad "2" smd rect
			(at 0 0.889 90)
			(size 0.508 0.508)
			(layers "F.Cu" "F.Mask" "F.Paste")
			(net "LED_POSTCODE_2_R")
		)
		(zone
			(layer "F.Cu")
			(hatch none 0.5)
			(connect_pads
				(clearance 0)
			)
			(min_thickness 0.25)
			(keepout
				(tracks allowed)
				(vias not_allowed)
				(pads allowed)
				(copperpour not_allowed)
				(footprints allowed)
			)
			(placement
				(enabled no)
				(sheetname "")
			)
			(fill
				(thermal_gap 0.5)
				(thermal_bridge_width 0.5)
				(island_removal_mode 0)
			)
			(polygon
				(pts
					(xy 489.6485 -143.622268) (xy 489.6485 -144.130268) (xy 490.0295 -144.130268) (xy 490.0295 -143.622268)
				)
			)
		)
		(zone
			(layer "F.Cu")
			(hatch none 0.5)
			(connect_pads
				(clearance 0)
			)
			(min_thickness 0.25)
			(keepout
				(tracks not_allowed)
				(vias allowed)
				(pads allowed)
				(copperpour not_allowed)
				(footprints allowed)
			)
			(placement
				(enabled no)
				(sheetname "")
			)
			(fill
				(thermal_gap 0.5)
				(thermal_bridge_width 0.5)
				(island_removal_mode 0)
			)
			(polygon
				(pts
					(xy 490.0295 -143.622268) (xy 490.0295 -144.130268) (xy 489.6485 -144.130268) (xy 489.6485 -143.622268)
				)
			)
		)
	)
)
